# S9S_MB_2U (Grand Teton) — schematic netlist excerpt (pin names and nets, part order shuffled) for the footprints in the layout excerpt that follows; sources: Cadence DE-HDL packaged netlist, KiCad conversion of 03242023_DA0F0TMBIJ0_F0T_Motherboard_J_brd_V01_OCP.brd

R2282  Q_RES  10K 1% CHIP  pkg 0402LF  page 191 : A = P3V3_AUX ; B = E1S_0_PRSNT
R2586  Q_RES  0 5% CHIP  pkg 0402LF  page 301 : A = HSC_EN ; B = HSC_EN_R

(kicad_pcb
	(version 20260206)
	(generator "pcbnew")
	(generator_version "10.0")
	(general
		(thickness 1.6)
		(legacy_teardrops no)
	)
	(paper "A4")
	(title_block
		(title "03242023_DA0F0TMBIJ0_F0T_Motherboard_J_brd_V01_OCP.brd")
		(comment 1 "Grand Teton / footprints 1965-1966 of 6105")
	)
	(layers
		(0 "F.Cu" signal "TOP")
		(4 "In1.Cu" signal "GND")
		(6 "In2.Cu" signal "IN1")
		(8 "In3.Cu" signal "GND1")
		(10 "In4.Cu" signal "IN2")
		(12 "In5.Cu" signal "GND2")
		(14 "In6.Cu" signal "IN3")
		(16 "In7.Cu" signal "GND3")
		(18 "In8.Cu" signal "VCC")
		(20 "In9.Cu" signal "VCC1")
		(22 "In10.Cu" signal "GND4")
		(24 "In11.Cu" signal "IN4")
		(26 "In12.Cu" signal "GND5")
		(28 "In13.Cu" signal "IN5")
		(30 "In14.Cu" signal "GND6")
		(32 "In15.Cu" signal "IN6")
		(34 "In16.Cu" signal "GND7")
		(2 "B.Cu" signal "BOTTOM")
		(9 "F.Adhes" user "F.Adhesive")
		(11 "B.Adhes" user "B.Adhesive")
		(13 "F.Paste" user "Package Geometry/Pastemask Top")
		(15 "B.Paste" user "Package Geometry/Pastemask Bottom")
		(5 "F.SilkS" user "Ref Des/Silkscreen Top")
		(7 "B.SilkS" user "Ref Des/Silkscreen Bottom")
		(1 "F.Mask" user "Board Geometry/Soldermask Top")
		(3 "B.Mask" user "Board Geometry/Soldermask Bottom")
		(17 "Dwgs.User" user "User.Drawings")
		(19 "Cmts.User" user "User.Comments")
		(21 "Eco1.User" user "User.Eco1")
		(23 "Eco2.User" user "User.Eco2")
		(25 "Edge.Cuts" user "Board Geometry/Outline")
		(27 "Margin" user)
		(31 "F.CrtYd" user "Package Geometry/Place Bound Top")
		(29 "B.CrtYd" user "Package Geometry/Place Bound Bottom")
		(35 "F.Fab" user "Ref Des/Assembly Top")
		(33 "B.Fab" user "Ref Des/Assembly Bottom")
	)
	(footprint ""
		(layer "F.Cu")
		(at 184.976008 -398.651222 180)
		(property "Reference" "R2586"
			(at 0 0 180)
			(layer "F.SilkS")
			(hide yes)
			(effects
				(font
					(size 1.27 1.27)
				)
			)
		)
		(property "Value" ""
			(at 0 0 180)
			(layer "F.Fab")
			(effects
				(font
					(size 1.27 1.27)
				)
			)
		)
		(duplicate_pad_numbers_are_jumpers no)
		(fp_line
			(start 0.7874 0.4064)
			(end -0.7874 0.4064)
			(stroke
				(width 0.1524)
				(type default)
			)
			(layer "F.SilkS")
		)
		(fp_line
			(start 0.7874 -0.4064)
			(end 0.7874 0.4064)
			(stroke
				(width 0.1524)
				(type default)
			)
			(layer "F.SilkS")
		)
		(fp_line
			(start -0.7874 0.4064)
			(end -0.7874 -0.4064)
			(stroke
				(width 0.1524)
				(type default)
			)
			(layer "F.SilkS")
		)
		(fp_line
			(start -0.7874 -0.4064)
			(end 0.7874 -0.4064)
			(stroke
				(width 0.1524)
				(type default)
			)
			(layer "F.SilkS")
		)
		(fp_line
			(start 0.67945 0.3048)
			(end 0.120396 0.3048)
			(stroke
				(width 0.1)
				(type default)
			)
			(layer "F.Fab")
		)
		(fp_line
			(start 0.67945 -0.3048)
			(end 0.67945 0.3048)
			(stroke
				(width 0.1)
				(type default)
			)
			(layer "F.Fab")
		)
		(fp_line
			(start 0.12065 -0.2794)
			(end 0.12065 -0.3048)
			(stroke
				(width 0.1)
				(type default)
			)
			(layer "F.Fab")
		)
		(fp_line
			(start 0.12065 -0.3048)
			(end 0.67945 -0.3048)
			(stroke
				(width 0.1)
				(type default)
			)
			(layer "F.Fab")
		)
		(fp_line
			(start 0.120396 0.3048)
			(end 0.120396 0.2794)
			(stroke
				(width 0.1)
				(type default)
			)
			(layer "F.Fab")
		)
		(fp_line
			(start 0.120396 0.2794)
			(end -0.12065 0.2794)
			(stroke
				(width 0.1)
				(type default)
			)
			(layer "F.Fab")
		)
		(fp_line
			(start -0.12065 0.3048)
			(end -0.67945 0.3048)
			(stroke
				(width 0.1)
				(type default)
			)
			(layer "F.Fab")
		)
		(fp_line
			(start -0.12065 0.2794)
			(end -0.12065 0.3048)
			(stroke
				(width 0.1)
				(type default)
			)
			(layer "F.Fab")
		)
		(fp_line
			(start -0.12065 -0.2794)
			(end 0.12065 -0.2794)
			(stroke
				(width 0.1)
				(type default)
			)
			(layer "F.Fab")
		)
		(fp_line
			(start -0.12065 -0.305054)
			(end -0.12065 -0.2794)
			(stroke
				(width 0.1)
				(type default)
			)
			(layer "F.Fab")
		)
		(fp_line
			(start -0.67945 0.3048)
			(end -0.67945 -0.305054)
			(stroke
				(width 0.1)
				(type default)
			)
			(layer "F.Fab")
		)
		(fp_line
			(start -0.67945 -0.305054)
			(end -0.12065 -0.305054)
			(stroke
				(width 0.1)
				(type default)
			)
			(layer "F.Fab")
		)
		(pad "1" smd circle
			(at -0.40005 0 180)
			(size 0 0)
			(layers "F.Cu" "F.Mask" "F.Paste")
			(net "HSC_EN")
		)
		(pad "2" smd circle
			(at 0.40005 0 180)
			(size 0 0)
			(layers "F.Cu" "F.Mask" "F.Paste")
			(net "HSC_EN_R")
		)
	)
	(footprint ""
		(layer "F.Cu")
		(at 141.240256 -64.313308)
		(property "Reference" "R2282"
			(at 0 0 0)
			(layer "F.SilkS")
			(hide yes)
			(effects
				(font
					(size 1.27 1.27)
				)
			)
		)
		(property "Value" ""
			(at 0 0 0)
			(layer "F.Fab")
			(effects
				(font
					(size 1.27 1.27)
				)
			)
		)
		(duplicate_pad_numbers_are_jumpers no)
		(fp_line
			(start -0.7874 -0.4064)
			(end 0.7874 -0.4064)
			(stroke
				(width 0.1524)
				(type default)
			)
			(layer "F.SilkS")
		)
		(fp_line
			(start -0.7874 0.4064)
			(end -0.7874 -0.4064)
			(stroke
				(width 0.1524)
				(type default)
			)
			(layer "F.SilkS")
		)
		(fp_line
			(start 0.7874 -0.4064)
			(end 0.7874 0.4064)
			(stroke
				(width 0.1524)
				(type default)
			)
			(layer "F.SilkS")
		)
		(fp_line
			(start 0.7874 0.4064)
			(end -0.7874 0.4064)
			(stroke
				(width 0.1524)
				(type default)
			)
			(layer "F.SilkS")
		)
		(fp_line
			(start -0.67945 -0.305054)
			(end -0.12065 -0.305054)
			(stroke
				(width 0.1)
				(type default)
			)
			(layer "F.Fab")
		)
		(fp_line
			(start -0.67945 0.3048)
			(end -0.67945 -0.305054)
			(stroke
				(width 0.1)
				(type default)
			)
			(layer "F.Fab")
		)
		(fp_line
			(start -0.12065 -0.305054)
			(end -0.12065 -0.2794)
			(stroke
				(width 0.1)
				(type default)
			)
			(layer "F.Fab")
		)
		(fp_line
			(start -0.12065 -0.2794)
			(end 0.12065 -0.2794)
			(stroke
				(width 0.1)
				(type default)
			)
			(layer "F.Fab")
		)
		(fp_line
			(start -0.12065 0.2794)
			(end -0.12065 0.3048)
			(stroke
				(width 0.1)
				(type default)
			)
			(layer "F.Fab")
		)
		(fp_line
			(start -0.12065 0.3048)
			(end -0.67945 0.3048)
			(stroke
				(width 0.1)
				(type default)
			)
			(layer "F.Fab")
		)
		(fp_line
			(start 0.120396 0.2794)
			(end -0.12065 0.2794)
			(stroke
				(width 0.1)
				(type default)
			)
			(layer "F.Fab")
		)
		(fp_line
			(start 0.120396 0.3048)
			(end 0.120396 0.2794)
			(stroke
				(width 0.1)
				(type default)
			)
			(layer "F.Fab")
		)
		(fp_line
			(start 0.12065 -0.3048)
			(end 0.67945 -0.3048)
			(stroke
				(width 0.1)
				(type default)
			)
			(layer "F.Fab")
		)
		(fp_line
			(start 0.12065 -0.2794)
			(end 0.12065 -0.3048)
			(stroke
				(width 0.1)
				(type default)
			)
			(layer "F.Fab")
		)
		(fp_line
			(start 0.67945 -0.3048)
			(end 0.67945 0.3048)
			(stroke
				(width 0.1)
				(type default)
			)
			(layer "F.Fab")
		)
		(fp_line
			(start 0.67945 0.3048)
			(end 0.120396 0.3048)
			(stroke
				(width 0.1)
				(type default)
			)
			(layer "F.Fab")
		)
		(pad "1" smd circle
			(at -0.40005 0)
			(size 0 0)
			(layers "F.Cu" "F.Mask" "F.Paste")
			(net "P3V3_AUX")
		)
		(pad "2" smd circle
			(at 0.40005 0)
			(size 0 0)
			(layers "F.Cu" "F.Mask" "F.Paste")
			(net "E1S_0_PRSNT")
		)
	)
)
